# BARRELEYE-G2-EXPANDER-EVT-HW-EBOM-X00-20161124-add_2nd_source_X06-20161207-Final.xls — POP_GA (bom)
| FOXCONN TECHNOLOGY GROUP |  |  |  |  |  |  |  |  |  |  |  |  |
| BILL OF MATERIAL |  |  |  |  |  |  |  |  |  |  |  |  |
| REV OF  BOM |  | CUSTOMER | <name> |  | CUSTOMER P/N |  | PRODUCT CODE |  | PWA  REV |  | DATE |  |
| Sourcing (Single/Sole/Multi) | Critical Commodity (Y or N) | Component Class (1, 2, other) | Customer PSL (Y or N) | Item Number | Foxconn P/N | Customer P/N | Part Description | Manufacturer  Full Name | Manufacturer  Part Number | Qty | RoHS Status | Location |
